(kicad_pcb
	(version 20260206)
	(generator "pcbnew")
	(generator_version "10.0")
	(general
		(thickness 1.6)
		(legacy_teardrops no)
	)
	(paper "A4")
	(title_block
		(title "v1-tray-backplane — T6M_tray_BP_c_1023_1120.brd")
		(comment 1 "Open CloudServer (Microsoft) / footprint 134 of 170 (J24), pads 1-54 of 54")
	)
	(layers
		(0 "F.Cu" signal "TOP")
		(4 "In1.Cu" signal "GND")
		(6 "In2.Cu" signal "IN1")
		(8 "In3.Cu" signal "VCC")
		(10 "In4.Cu" signal "VCC1")
		(12 "In5.Cu" signal "IN2")
		(14 "In6.Cu" signal "GND1")
		(2 "B.Cu" signal "BOTTOM")
		(9 "F.Adhes" user "F.Adhesive")
		(11 "B.Adhes" user "B.Adhesive")
		(13 "F.Paste" user "Package Geometry/Pastemask Top")
		(15 "B.Paste" user "Package Geometry/Pastemask Bottom")
		(5 "F.SilkS" user "Ref Des/Silkscreen Top")
		(7 "B.SilkS" user "Ref Des/Silkscreen Bottom")
		(1 "F.Mask" user "Board Geometry/Soldermask Top")
		(3 "B.Mask" user "Board Geometry/Soldermask Bottom")
		(17 "Dwgs.User" user "User.Drawings")
		(19 "Cmts.User" user "User.Comments")
		(21 "Eco1.User" user "User.Eco1")
		(23 "Eco2.User" user "User.Eco2")
		(25 "Edge.Cuts" user "Board Geometry/Outline")
		(27 "Margin" user)
		(31 "F.CrtYd" user "Package Geometry/Place Bound Top")
		(29 "B.CrtYd" user "Package Geometry/Place Bound Bottom")
		(35 "F.Fab" user "Ref Des/Assembly Top")
		(33 "B.Fab" user "Ref Des/Assembly Bottom")
	)
	(footprint ""
		(layer "F.Cu")
		(at 128.530096 -2.100072 180)
		(property "Reference" "J24"
			(at -4.923028 -1.445768 90)
			(unlocked yes)
			(layer "F.SilkS")
			(effects
				(font
					(size 0.7874 0.5842)
					(thickness 0.1524)
				)
				(justify left)
			)
		)
		(property "Value" ""
			(at 0 0 180)
			(layer "F.Fab")
			(effects
				(font
					(size 1.27 1.27)
				)
			)
		)
		(duplicate_pad_numbers_are_jumpers no)
		(pad "A1" thru_hole rect
			(at 0 0)
			(size 0.9144 0.9144)
			(drill 0.508)
			(layers "*.Cu" "*.Mask")
			(remove_unused_layers no)
			(net "ENET1G_1_MDI0P")
			(clearance 0.0508)
			(thermal_gap 0.0508)
			(padstack
				(mode front_inner_back)
				(layer "Inner"
					(shape circle)
					(size 0.9144 0.9144)
					(clearance 0.0508)
				)
				(layer "B.Cu"
					(shape rect)
					(size 0.9144 0.9144)
					(clearance 0.0508)
				)
			)
		)
		(pad "A2" thru_hole circle
			(at 1.999996 -0.100076)
			(size 0.9144 0.9144)
			(drill 0.508)
			(layers "*.Cu" "*.Mask")
			(remove_unused_layers no)
			(net "GND")
			(clearance 0.0508)
			(thermal_gap 0.0508)
		)
		(pad "A3" thru_hole circle
			(at 3.999992 0)
			(size 0.9144 0.9144)
			(drill 0.508)
			(layers "*.Cu" "*.Mask")
			(remove_unused_layers no)
			(net "ENET1G_1_MDI3P")
			(clearance 0.0508)
			(thermal_gap 0.0508)
		)
		(pad "A4" thru_hole circle
			(at 5.999988 -0.100076)
			(size 0.9144 0.9144)
			(drill 0.508)
			(layers "*.Cu" "*.Mask")
			(remove_unused_layers no)
			(net "GND")
			(clearance 0.0508)
			(thermal_gap 0.0508)
		)
		(pad "A5" thru_hole circle
			(at 7.999984 0)
			(size 0.9144 0.9144)
			(drill 0.508)
			(layers "*.Cu" "*.Mask")
			(remove_unused_layers no)
			(net "ENET1G_2_MDI1P")
			(clearance 0.0508)
			(thermal_gap 0.0508)
		)
		(pad "A6" thru_hole circle
			(at 9.99998 -0.100076)
			(size 0.9144 0.9144)
			(drill 0.508)
			(layers "*.Cu" "*.Mask")
			(remove_unused_layers no)
			(net "GND")
			(clearance 0.0508)
			(thermal_gap 0.0508)
		)
		(pad "B1" thru_hole circle
			(at 0 1.400048)
			(size 0.9144 0.9144)
			(drill 0.508)
			(layers "*.Cu" "*.Mask")
			(remove_unused_layers no)
			(net "ENET1G_1_MDI0N")
			(clearance 0.0508)
			(thermal_gap 0.0508)
		)
		(pad "B2" thru_hole circle
			(at 1.999996 1.299972)
			(size 0.9144 0.9144)
			(drill 0.508)
			(layers "*.Cu" "*.Mask")
			(remove_unused_layers no)
			(net "ENET1G_1_MDI2P")
			(clearance 0.0508)
			(thermal_gap 0.0508)
		)
		(pad "B3" thru_hole circle
			(at 3.999992 1.400048)
			(size 0.9144 0.9144)
			(drill 0.508)
			(layers "*.Cu" "*.Mask")
			(remove_unused_layers no)
			(net "ENET1G_1_MDI3N")
			(clearance 0.0508)
			(thermal_gap 0.0508)
		)
		(pad "B4" thru_hole circle
			(at 5.999988 1.299972)
			(size 0.9144 0.9144)
			(drill 0.508)
			(layers "*.Cu" "*.Mask")
			(remove_unused_layers no)
			(net "ENET1G_2_MDI0P")
			(clearance 0.0508)
			(thermal_gap 0.0508)
		)
		(pad "B5" thru_hole circle
			(at 7.999984 1.400048)
			(size 0.9144 0.9144)
			(drill 0.508)
			(layers "*.Cu" "*.Mask")
			(remove_unused_layers no)
			(net "ENET1G_2_MDI1N")
			(clearance 0.0508)
			(thermal_gap 0.0508)
		)
		(pad "B6" thru_hole circle
			(at 9.99998 1.299972)
			(size 0.9144 0.9144)
			(drill 0.508)
			(layers "*.Cu" "*.Mask")
			(remove_unused_layers no)
			(net "ENET1G_2_MDI3P")
			(clearance 0.0508)
			(thermal_gap 0.0508)
		)
		(pad "C1" thru_hole circle
			(at 0 2.800096)
			(size 0.9144 0.9144)
			(drill 0.508)
			(layers "*.Cu" "*.Mask")
			(remove_unused_layers no)
			(net "GND")
			(clearance 0.0508)
			(thermal_gap 0.0508)
		)
		(pad "C2" thru_hole circle
			(at 1.999996 2.70002)
			(size 0.9144 0.9144)
			(drill 0.508)
			(layers "*.Cu" "*.Mask")
			(remove_unused_layers no)
			(net "ENET1G_1_MDI2N")
			(clearance 0.0508)
			(thermal_gap 0.0508)
		)
		(pad "C3" thru_hole circle
			(at 3.999992 2.800096)
			(size 0.9144 0.9144)
			(drill 0.508)
			(layers "*.Cu" "*.Mask")
			(remove_unused_layers no)
			(net "GND")
			(clearance 0.0508)
			(thermal_gap 0.0508)
		)
		(pad "C4" thru_hole circle
			(at 5.999988 2.70002)
			(size 0.9144 0.9144)
			(drill 0.508)
			(layers "*.Cu" "*.Mask")
			(remove_unused_layers no)
			(net "ENET1G_2_MDI0N")
			(clearance 0.0508)
			(thermal_gap 0.0508)
		)
		(pad "C5" thru_hole circle
			(at 7.999984 2.800096)
			(size 0.9144 0.9144)
			(drill 0.508)
			(layers "*.Cu" "*.Mask")
			(remove_unused_layers no)
			(net "GND")
			(clearance 0.0508)
			(thermal_gap 0.0508)
		)
		(pad "C6" thru_hole circle
			(at 9.99998 2.70002)
			(size 0.9144 0.9144)
			(drill 0.508)
			(layers "*.Cu" "*.Mask")
			(remove_unused_layers no)
			(net "ENET1G_2_MDI3N")
			(clearance 0.0508)
			(thermal_gap 0.0508)
		)
		(pad "D1" thru_hole circle
			(at 0 4.19989)
			(size 0.9144 0.9144)
			(drill 0.508)
			(layers "*.Cu" "*.Mask")
			(remove_unused_layers no)
			(net "ENET10G_1_RDP")
			(clearance 0.0508)
			(thermal_gap 0.0508)
		)
		(pad "D2" thru_hole circle
			(at 1.999996 4.100068)
			(size 0.9144 0.9144)
			(drill 0.508)
			(layers "*.Cu" "*.Mask")
			(remove_unused_layers no)
			(net "GND")
			(clearance 0.0508)
			(thermal_gap 0.0508)
		)
		(pad "D3" thru_hole circle
			(at 3.999992 4.19989)
			(size 0.9144 0.9144)
			(drill 0.508)
			(layers "*.Cu" "*.Mask")
			(remove_unused_layers no)
			(net "ENET10G_1_SDA")
			(clearance 0.0508)
			(thermal_gap 0.0508)
		)
		(pad "D4" thru_hole circle
			(at 5.999988 4.100068)
			(size 0.9144 0.9144)
			(drill 0.508)
			(layers "*.Cu" "*.Mask")
			(remove_unused_layers no)
			(net "GND")
			(clearance 0.0508)
			(thermal_gap 0.0508)
		)
		(pad "D5" thru_hole circle
			(at 7.999984 4.19989)
			(size 0.9144 0.9144)
			(drill 0.508)
			(layers "*.Cu" "*.Mask")
			(remove_unused_layers no)
			(net "ENET1G_2_MDI2P")
			(clearance 0.0508)
			(thermal_gap 0.0508)
		)
		(pad "D6" thru_hole circle
			(at 9.99998 4.100068)
			(size 0.9144 0.9144)
			(drill 0.508)
			(layers "*.Cu" "*.Mask")
			(remove_unused_layers no)
			(net "GND")
			(clearance 0.0508)
			(thermal_gap 0.0508)
		)
		(pad "E1" thru_hole circle
			(at 0 5.599938)
			(size 0.9144 0.9144)
			(drill 0.508)
			(layers "*.Cu" "*.Mask")
			(remove_unused_layers no)
			(net "ENET10G_1_RDN")
			(clearance 0.0508)
			(thermal_gap 0.0508)
		)
		(pad "E2" thru_hole circle
			(at 1.999996 5.500116)
			(size 0.9144 0.9144)
			(drill 0.508)
			(layers "*.Cu" "*.Mask")
			(remove_unused_layers no)
			(net "ENET1G_1_MDI1P")
			(clearance 0.0508)
			(thermal_gap 0.0508)
		)
		(pad "E3" thru_hole circle
			(at 3.999992 5.599938)
			(size 0.9144 0.9144)
			(drill 0.508)
			(layers "*.Cu" "*.Mask")
			(remove_unused_layers no)
			(net "ENET10G_1_SCL")
			(clearance 0.0508)
			(thermal_gap 0.0508)
		)
		(pad "E4" thru_hole circle
			(at 5.999988 5.500116)
			(size 0.9144 0.9144)
			(drill 0.508)
			(layers "*.Cu" "*.Mask")
			(remove_unused_layers no)
			(net "ENET10G_2_SDA")
			(clearance 0.0508)
			(thermal_gap 0.0508)
		)
		(pad "E5" thru_hole circle
			(at 7.999984 5.599938)
			(size 0.9144 0.9144)
			(drill 0.508)
			(layers "*.Cu" "*.Mask")
			(remove_unused_layers no)
			(net "ENET1G_2_MDI2N")
			(clearance 0.0508)
			(thermal_gap 0.0508)
		)
		(pad "E6" thru_hole circle
			(at 9.99998 5.500116)
			(size 0.9144 0.9144)
			(drill 0.508)
			(layers "*.Cu" "*.Mask")
			(remove_unused_layers no)
			(net "ENET10G_2_RDP")
			(clearance 0.0508)
			(thermal_gap 0.0508)
		)
		(pad "F1" thru_hole circle
			(at 0 6.999986)
			(size 0.9144 0.9144)
			(drill 0.508)
			(layers "*.Cu" "*.Mask")
			(remove_unused_layers no)
			(net "GND")
			(clearance 0.0508)
			(thermal_gap 0.0508)
		)
		(pad "F2" thru_hole circle
			(at 1.999996 6.89991)
			(size 0.9144 0.9144)
			(drill 0.508)
			(layers "*.Cu" "*.Mask")
			(remove_unused_layers no)
			(net "ENET1G_1_MDI1N")
			(clearance 0.0508)
			(thermal_gap 0.0508)
		)
		(pad "F3" thru_hole circle
			(at 3.999992 6.999986)
			(size 0.9144 0.9144)
			(drill 0.508)
			(layers "*.Cu" "*.Mask")
			(remove_unused_layers no)
			(net "SKU_PIN_BLAD1_1")
			(clearance 0.0508)
			(thermal_gap 0.0508)
		)
		(pad "F4" thru_hole circle
			(at 5.999988 6.89991)
			(size 0.9144 0.9144)
			(drill 0.508)
			(layers "*.Cu" "*.Mask")
			(remove_unused_layers no)
			(net "ENET10G_2_SCL")
			(clearance 0.0508)
			(thermal_gap 0.0508)
		)
		(pad "F5" thru_hole circle
			(at 7.999984 6.999986)
			(size 0.9144 0.9144)
			(drill 0.508)
			(layers "*.Cu" "*.Mask")
			(remove_unused_layers no)
			(net "GND")
			(clearance 0.0508)
			(thermal_gap 0.0508)
		)
		(pad "F6" thru_hole circle
			(at 9.99998 6.89991)
			(size 0.9144 0.9144)
			(drill 0.508)
			(layers "*.Cu" "*.Mask")
			(remove_unused_layers no)
			(net "ENET10G_2_RDN")
			(clearance 0.0508)
			(thermal_gap 0.0508)
		)
		(pad "G1" thru_hole circle
			(at 0 8.400034)
			(size 0.9144 0.9144)
			(drill 0.508)
			(layers "*.Cu" "*.Mask")
			(remove_unused_layers no)
			(net "ENET10G_1_TDP")
			(clearance 0.0508)
			(thermal_gap 0.0508)
		)
		(pad "G2" thru_hole circle
			(at 1.999996 8.299958)
			(size 0.9144 0.9144)
			(drill 0.508)
			(layers "*.Cu" "*.Mask")
			(remove_unused_layers no)
			(net "GND")
			(clearance 0.0508)
			(thermal_gap 0.0508)
		)
		(pad "G3" thru_hole circle
			(at 3.999992 8.400034)
			(size 0.9144 0.9144)
			(drill 0.508)
			(layers "*.Cu" "*.Mask")
			(remove_unused_layers no)
			(net "NODE1_RXD")
			(clearance 0.0508)
			(thermal_gap 0.0508)
		)
		(pad "G4" thru_hole circle
			(at 5.999988 8.299958)
			(size 0.9144 0.9144)
			(drill 0.508)
			(layers "*.Cu" "*.Mask")
			(remove_unused_layers no)
			(net "NODE2_RXD")
			(clearance 0.0508)
			(thermal_gap 0.0508)
		)
		(pad "G5" thru_hole circle
			(at 7.999984 8.400034)
			(size 0.9144 0.9144)
			(drill 0.508)
			(layers "*.Cu" "*.Mask")
			(remove_unused_layers no)
			(net "NODE2_EN")
			(clearance 0.0508)
			(thermal_gap 0.0508)
		)
		(pad "G6" thru_hole circle
			(at 9.99998 8.299958)
			(size 0.9144 0.9144)
			(drill 0.508)
			(layers "*.Cu" "*.Mask")
			(remove_unused_layers no)
			(net "GND")
			(clearance 0.0508)
			(thermal_gap 0.0508)
		)
		(pad "H1" thru_hole circle
			(at 0 9.800082)
			(size 0.9144 0.9144)
			(drill 0.508)
			(layers "*.Cu" "*.Mask")
			(remove_unused_layers no)
			(net "ENET10G_1_TDN")
			(clearance 0.0508)
			(thermal_gap 0.0508)
		)
		(pad "H2" thru_hole circle
			(at 1.999996 9.700006)
			(size 0.9144 0.9144)
			(drill 0.508)
			(layers "*.Cu" "*.Mask")
			(remove_unused_layers no)
			(net "NODE1_EN")
			(clearance 0.0508)
			(thermal_gap 0.0508)
		)
		(pad "H3" thru_hole circle
			(at 3.999992 9.800082)
			(size 0.9144 0.9144)
			(drill 0.508)
			(layers "*.Cu" "*.Mask")
			(remove_unused_layers no)
			(net "NODE1_TXD")
			(clearance 0.0508)
			(thermal_gap 0.0508)
		)
		(pad "H4" thru_hole circle
			(at 5.999988 9.700006)
			(size 0.9144 0.9144)
			(drill 0.508)
			(layers "*.Cu" "*.Mask")
			(remove_unused_layers no)
			(net "NODE2_TXD")
			(clearance 0.0508)
			(thermal_gap 0.0508)
		)
		(pad "H5" thru_hole circle
			(at 7.999984 9.800082)
			(size 0.9144 0.9144)
			(drill 0.508)
			(layers "*.Cu" "*.Mask")
			(remove_unused_layers no)
			(net "SFP2_PRESENT_N")
			(clearance 0.0508)
			(thermal_gap 0.0508)
		)
		(pad "H6" thru_hole circle
			(at 9.99998 9.700006)
			(size 0.9144 0.9144)
			(drill 0.508)
			(layers "*.Cu" "*.Mask")
			(remove_unused_layers no)
			(net "ENET10G_2_TDP")
			(clearance 0.0508)
			(thermal_gap 0.0508)
		)
		(pad "I1" thru_hole circle
			(at 0 11.199876)
			(size 0.9144 0.9144)
			(drill 0.508)
			(layers "*.Cu" "*.Mask")
			(remove_unused_layers no)
			(net "GND")
			(clearance 0.0508)
			(thermal_gap 0.0508)
		)
		(pad "I2" thru_hole circle
			(at 1.999996 11.100054)
			(size 0.9144 0.9144)
			(drill 0.508)
			(layers "*.Cu" "*.Mask")
			(remove_unused_layers no)
			(net "SFP1_PRESENT_N")
			(clearance 0.0508)
			(thermal_gap 0.0508)
		)
		(pad "I3" thru_hole circle
			(at 3.999992 11.199876)
			(size 0.9144 0.9144)
			(drill 0.508)
			(layers "*.Cu" "*.Mask")
			(remove_unused_layers no)
			(net "P3V3_BLAD1")
			(clearance 0.0508)
			(thermal_gap 0.0508)
		)
		(pad "I4" thru_hole circle
			(at 5.999988 11.100054)
			(size 0.9144 0.9144)
			(drill 0.508)
			(layers "*.Cu" "*.Mask")
			(remove_unused_layers no)
			(net "SKU_PIN_BLAD1_2")
			(clearance 0.0508)
			(thermal_gap 0.0508)
		)
		(pad "I5" thru_hole circle
			(at 7.999984 11.199876)
			(size 0.9144 0.9144)
			(drill 0.508)
			(layers "*.Cu" "*.Mask")
			(remove_unused_layers no)
			(net "BLADE1_MATED_N")
			(clearance 0.0508)
			(thermal_gap 0.0508)
		)
		(pad "I6" thru_hole circle
			(at 9.99998 11.100054)
			(size 0.9144 0.9144)
			(drill 0.508)
			(layers "*.Cu" "*.Mask")
			(remove_unused_layers no)
			(net "ENET10G_2_TDN")
			(clearance 0.0508)
			(thermal_gap 0.0508)
		)
	)
)
